FILE_TYPE = CONNECTIVITY;
{Allegro Design Entry HDL 17.4-2019 S026 (4007227) 1/17/2022}
"PAGE_NUMBER" = 97;
0"NC";
1"GND\g";
2"GND\g";
3"P3V3\g";
4"P3V3\g";
5"P3V3_AUX\g";
6"M_A_CPU1_SB_DQ<31:0>";
7"M_A_CPU1_SA_CA<6:0>";
8"M_A_CPU1_SA_DQS_DP<9:0>";
9"M_A_CPU1_SA_DQ<31:0>";
10"M_A_CPU1_SB_DQS_DP<9:0>";
11"M_A_CPU1_SB_DQS_DN<9:0>";
12"M_A_CPU1_SA_DQS_DN<9:0>";
13"M_A_CPU1_SB_CB<7:0>";
14"M_A_CPU1_SA_CB<7:0>";
15"M_A_CPU1_SB_CA<6:0>";
16"M_A_CPU1_SB_RSP<0>";
17"I3C_SPD_DDRAF_CPU1_SDA";
18"I3C_SPD_DDRA_CPU1_SDA";
19"I3C_SPD_DDRAF_CPU1_SCL";
20"PWRGD_CHA_CPU1_DIMM0";
21"PD_CHA_CPU1_DIMM0_SAA";
22"P3V3_AUX\g";
23"M_A_CPU1_ALERT_N";
24"I3C_SPD_DDRA_CPU1_SCL";
25"M_A_CPU1_RESET_N";
26"M_A_CPU1_SB_CB<7>";
27"M_A_CPU1_SA_CB<0>";
28"M_A_CPU1_SA_CB<1>";
29"M_A_CPU1_SB_CB<3>";
30"M_A_CPU1_SB_CB<4>";
31"M_A_CPU1_SB_CB<5>";
32"M_A_CPU1_SB_CB<6>";
33"M_A_CPU1_SB_DQ<30>";
34"M_A_CPU1_SB_DQ<29>";
35"M_A_CPU1_SA_CS_N<0>";
36"PWRGD_CHAF_CPU1_R1";
37"PWRGD_CHAF_CPU1";
38"PWRGD_CHAF_CPU1";
39"GND\g";
40"P3V3_AUX\g";
41"P3V3_AUX\g";
42"P12V_MEM_CPU1\g";
43"GND\g";
44"GND\g";
45"PWRGD_CHAF_CPU1_R2";
46"PD_CHA_CPU1_DIMM0_SAA";
47"M_A_CPU1_SA_DQ<31>";
48"M_A_CPU1_SA_CB<7>";
49"M_A_CPU1_SA_CB<4>";
50"M_A_CPU1_SB_CA<0>";
51"M_A_CPU1_SB_CA<1>";
52"M_A_CPU1_SA_CA<2>";
53"M_A_CPU1_SB_CA<2>";
54"M_A_CPU1_SB_CA<3>";
55"M_A_CPU1_SA_CA<4>";
56"M_A_CPU1_SB_CA<4>";
57"M_A_CPU1_SA_CA<5>";
58"M_A_CPU1_SB_CA<5>";
59"M_A_CPU1_SB_CA<6>";
60"M_A_CPU1_SA_CB<6>";
61"M_A_CPU1_SA_CB<5>";
62"M_A_CPU1_SA_CB<3>";
63"M_A_CPU1_SA_CB<2>";
64"M_A_CPU1_SB_CB<2>";
65"M_A_CPU1_SB_CB<1>";
66"M_A_CPU1_SB_CB<0>";
67"M_A_CPU1_CLK_DN<0>";
68"M_A_CPU1_CLK_DP<0>";
69"M_A_CPU1_SB_CS_N<0>";
70"M_A_CPU1_SA_CS_N<1>";
71"M_A_CPU1_SB_CS_N<1>";
72"M_A_CPU1_SA_DQ<30>";
73"M_A_CPU1_SA_DQ<29>";
74"M_A_CPU1_SA_DQ<26>";
75"M_A_CPU1_SA_DQ<25>";
76"M_A_CPU1_SA_DQ<23>";
77"M_A_CPU1_SA_DQ<20>";
78"M_A_CPU1_SA_DQ<19>";
79"M_A_CPU1_SA_DQ<16>";
80"M_A_CPU1_SA_DQ<15>";
81"M_A_CPU1_SA_DQ<14>";
82"M_A_CPU1_SA_DQ<13>";
83"M_A_CPU1_SA_DQ<12>";
84"M_A_CPU1_SA_DQ<11>";
85"M_A_CPU1_SA_DQ<10>";
86"M_A_CPU1_SA_DQ<9>";
87"M_A_CPU1_SA_DQ<8>";
88"M_A_CPU1_SA_DQ<7>";
89"M_A_CPU1_SA_DQ<6>";
90"M_A_CPU1_SA_DQ<5>";
91"M_A_CPU1_SA_DQ<4>";
92"M_A_CPU1_SA_DQ<3>";
93"M_A_CPU1_SA_DQ<2>";
94"M_A_CPU1_SA_DQ<1>";
95"M_A_CPU1_SA_DQ<0>";
96"M_A_CPU1_SB_DQ<31>";
97"M_A_CPU1_SB_DQ<28>";
98"M_A_CPU1_SB_DQ<27>";
99"M_A_CPU1_SB_DQ<26>";
100"M_A_CPU1_SB_DQ<25>";
101"M_A_CPU1_SB_DQ<24>";
102"M_A_CPU1_SB_DQ<23>";
103"M_A_CPU1_SB_DQ<22>";
104"M_A_CPU1_SB_DQ<20>";
105"M_A_CPU1_SB_DQ<19>";
106"M_A_CPU1_SB_DQ<18>";
107"M_A_CPU1_SB_DQ<17>";
108"M_A_CPU1_SB_DQ<16>";
109"M_A_CPU1_SB_DQ<15>";
110"M_A_CPU1_SB_DQ<14>";
111"M_A_CPU1_SB_DQ<13>";
112"M_A_CPU1_SB_DQ<12>";
113"M_A_CPU1_SB_DQ<11>";
114"M_A_CPU1_SB_DQ<10>";
115"M_A_CPU1_SB_DQ<9>";
116"M_A_CPU1_SB_DQ<8>";
117"M_A_CPU1_SB_DQ<7>";
118"M_A_CPU1_SB_DQ<3>";
119"M_A_CPU1_SB_DQ<2>";
120"M_A_CPU1_SB_DQ<1>";
121"M_A_CPU1_SB_DQ<0>";
122"M_A_CPU1_SA_RSP<0>";
123"M_A_CPU1_SA_PAR";
124"M_A_CPU1_SB_PAR";
125"M_A_CPU1_SA_DQ<28>";
126"M_A_CPU1_SA_DQ<27>";
127"M_A_CPU1_SA_CA<0>";
128"M_A_CPU1_SA_DQ<24>";
129"M_A_CPU1_SA_DQ<18>";
130"M_A_CPU1_SA_DQ<17>";
131"M_A_CPU1_SA_DQS_DN<7>";
132"M_A_CPU1_SA_DQS_DP<6>";
133"M_A_CPU1_SB_DQS_DP<8>";
134"M_A_CPU1_SB_DQS_DN<8>";
135"M_A_CPU1_SB_DQS_DP<7>";
136"M_A_CPU1_SA_DQS_DN<0>";
137"M_A_CPU1_SA_DQS_DP<0>";
138"M_A_CPU1_SB_DQS_DN<0>";
139"M_A_CPU1_SB_DQS_DP<0>";
140"M_A_CPU1_SA_DQS_DN<1>";
141"M_A_CPU1_SA_DQS_DP<1>";
142"M_A_CPU1_SB_DQS_DN<1>";
143"M_A_CPU1_SB_DQS_DP<1>";
144"M_A_CPU1_SA_DQS_DN<2>";
145"M_A_CPU1_SA_DQS_DP<2>";
146"M_A_CPU1_SB_DQS_DN<2>";
147"M_A_CPU1_SB_DQS_DP<2>";
148"M_A_CPU1_SA_DQS_DN<3>";
149"M_A_CPU1_SA_DQS_DP<3>";
150"M_A_CPU1_SB_DQS_DN<3>";
151"M_A_CPU1_SB_DQS_DP<3>";
152"M_A_CPU1_SA_DQS_DN<4>";
153"M_A_CPU1_SA_DQS_DP<4>";
154"M_A_CPU1_SB_DQS_DN<4>";
155"M_A_CPU1_SB_DQS_DP<4>";
156"M_A_CPU1_SA_DQS_DN<5>";
157"M_A_CPU1_SA_DQS_DP<5>";
158"M_A_CPU1_SB_DQS_DN<5>";
159"M_A_CPU1_SB_DQS_DP<5>";
160"M_A_CPU1_SA_DQS_DN<6>";
161"M_A_CPU1_SB_DQS_DN<6>";
162"M_A_CPU1_SB_DQS_DP<6>";
163"M_A_CPU1_SA_DQS_DP<7>";
164"M_A_CPU1_SB_DQS_DN<7>";
165"M_A_CPU1_SA_DQS_DN<8>";
166"M_A_CPU1_SA_DQS_DP<8>";
167"M_A_CPU1_SA_DQS_DN<9>";
168"M_A_CPU1_SB_DQS_DN<9>";
169"M_A_CPU1_SB_DQS_DP<9>";
170"M_A_CPU1_SA_DQ<22>";
171"M_A_CPU1_SA_DQ<21>";
172"M_A_CPU1_SA_DQS_DP<9>";
173"M_A_CPU1_SA_CA<1>";
174"M_A_CPU1_SA_CA<3>";
175"M_A_CPU1_SA_CA<6>";
176"M_A_CPU1_SB_DQ<21>";
177"M_A_CPU1_SB_DQ<5>";
178"M_A_CPU1_SB_DQ<6>";
179"M_A_CPU1_SB_DQ<4>";
180"PWRGD_CHAF_CPU1";
%"TAP"
"1","(-5750,4175)","0","mstr_standard","I100";
;
CDS_LIB"mstr_standard"
BODY_TYPE"PLUMBING"
HDL_TAP"TRUE";
"B \NAC \NWC"9;
"S \NAC"
BN"5"90;
%"TAP"
"1","(-5750,4325)","0","mstr_standard","I101";
;
CDS_LIB"mstr_standard"
BODY_TYPE"PLUMBING"
HDL_TAP"TRUE";
"B \NAC \NWC"9;
"S \NAC"
BN"8"87;
%"TAP"
"1","(-5750,4375)","0","mstr_standard","I102";
;
CDS_LIB"mstr_standard"
BODY_TYPE"PLUMBING"
HDL_TAP"TRUE";
"B \NAC \NWC"9;
"S \NAC"
BN"9"86;
%"TAP"
"1","(-5750,4275)","0","mstr_standard","I103";
;
CDS_LIB"mstr_standard"
BODY_TYPE"PLUMBING"
HDL_TAP"TRUE";
"B \NAC \NWC"9;
"S \NAC"
BN"7"88;
%"TAP"
"1","(-5750,4525)","0","mstr_standard","I104";
;
CDS_LIB"mstr_standard"
BODY_TYPE"PLUMBING"
HDL_TAP"TRUE";
"B \NAC \NWC"9;
"S \NAC"
BN"12"83;
%"TAP"
"1","(-5750,4475)","0","mstr_standard","I105";
;
CDS_LIB"mstr_standard"
BODY_TYPE"PLUMBING"
HDL_TAP"TRUE";
"B \NAC \NWC"9;
"S \NAC"
BN"11"84;
%"TAP"
"1","(-5750,4425)","0","mstr_standard","I106";
;
CDS_LIB"mstr_standard"
BODY_TYPE"PLUMBING"
HDL_TAP"TRUE";
"B \NAC \NWC"9;
"S \NAC"
BN"10"85;
%"TAP"
"1","(-5750,4575)","0","mstr_standard","I107";
;
CDS_LIB"mstr_standard"
BODY_TYPE"PLUMBING"
HDL_TAP"TRUE";
"B \NAC \NWC"9;
"S \NAC"
BN"13"82;
%"TAP"
"1","(-5750,4625)","0","mstr_standard","I108";
;
CDS_LIB"mstr_standard"
BODY_TYPE"PLUMBING"
HDL_TAP"TRUE";
"B \NAC \NWC"9;
"S \NAC"
BN"14"81;
%"TAP"
"1","(-5750,4775)","0","mstr_standard","I109";
;
CDS_LIB"mstr_standard"
BODY_TYPE"PLUMBING"
HDL_TAP"TRUE";
"B \NAC \NWC"9;
"S \NAC"
BN"17"130;
%"TAP"
"1","(-5750,4725)","0","mstr_standard","I110";
;
CDS_LIB"mstr_standard"
BODY_TYPE"PLUMBING"
HDL_TAP"TRUE";
"B \NAC \NWC"9;
"S \NAC"
BN"16"79;
%"TAP"
"1","(-5750,4675)","0","mstr_standard","I111";
;
CDS_LIB"mstr_standard"
BODY_TYPE"PLUMBING"
HDL_TAP"TRUE";
"B \NAC \NWC"9;
"S \NAC"
BN"15"80;
%"TAP"
"1","(-5750,4825)","0","mstr_standard","I112";
;
CDS_LIB"mstr_standard"
BODY_TYPE"PLUMBING"
HDL_TAP"TRUE";
"B \NAC \NWC"9;
"S \NAC"
BN"18"129;
%"TAP"
"1","(-5750,4875)","0","mstr_standard","I113";
;
CDS_LIB"mstr_standard"
BODY_TYPE"PLUMBING"
HDL_TAP"TRUE";
"B \NAC \NWC"9;
"S \NAC"
BN"19"78;
%"TAP"
"1","(-5750,5025)","0","mstr_standard","I114";
;
CDS_LIB"mstr_standard"
BODY_TYPE"PLUMBING"
HDL_TAP"TRUE";
"B \NAC \NWC"9;
"S \NAC"
BN"22"170;
%"TAP"
"1","(-5750,4975)","0","mstr_standard","I115";
;
CDS_LIB"mstr_standard"
BODY_TYPE"PLUMBING"
HDL_TAP"TRUE";
"B \NAC \NWC"9;
"S \NAC"
BN"21"171;
%"TAP"
"1","(-5750,4925)","0","mstr_standard","I116";
;
CDS_LIB"mstr_standard"
BODY_TYPE"PLUMBING"
HDL_TAP"TRUE";
"B \NAC \NWC"9;
"S \NAC"
BN"20"77;
%"TAP"
"1","(-5750,5125)","0","mstr_standard","I117";
;
CDS_LIB"mstr_standard"
BODY_TYPE"PLUMBING"
HDL_TAP"TRUE";
"B \NAC \NWC"9;
"S \NAC"
BN"24"128;
%"TAP"
"1","(-5750,5075)","0","mstr_standard","I118";
;
CDS_LIB"mstr_standard"
BODY_TYPE"PLUMBING"
HDL_TAP"TRUE";
"B \NAC \NWC"9;
"S \NAC"
BN"23"76;
%"TAP"
"1","(-5750,5225)","0","mstr_standard","I119";
;
CDS_LIB"mstr_standard"
BODY_TYPE"PLUMBING"
HDL_TAP"TRUE";
"B \NAC \NWC"9;
"S \NAC"
BN"26"74;
%"TAP"
"1","(-5750,5275)","0","mstr_standard","I120";
;
CDS_LIB"mstr_standard"
BODY_TYPE"PLUMBING"
HDL_TAP"TRUE";
"B \NAC \NWC"9;
"S \NAC"
BN"27"126;
%"TAP"
"1","(-5750,5175)","0","mstr_standard","I121";
;
CDS_LIB"mstr_standard"
BODY_TYPE"PLUMBING"
HDL_TAP"TRUE";
"B \NAC \NWC"9;
"S \NAC"
BN"25"75;
%"TAP"
"1","(-5750,5425)","0","mstr_standard","I122";
;
CDS_LIB"mstr_standard"
BODY_TYPE"PLUMBING"
HDL_TAP"TRUE";
"B \NAC \NWC"9;
"S \NAC"
BN"30"72;
%"TAP"
"1","(-5750,5325)","0","mstr_standard","I123";
;
CDS_LIB"mstr_standard"
BODY_TYPE"PLUMBING"
HDL_TAP"TRUE";
"B \NAC \NWC"9;
"S \NAC"
BN"28"125;
%"TAP"
"1","(-5750,5375)","0","mstr_standard","I124";
;
CDS_LIB"mstr_standard"
BODY_TYPE"PLUMBING"
HDL_TAP"TRUE";
"B \NAC \NWC"9;
"S \NAC"
BN"29"73;
%"TAP"
"1","(-5750,5475)","0","mstr_standard","I125";
;
CDS_LIB"mstr_standard"
BODY_TYPE"PLUMBING"
HDL_TAP"TRUE";
"B \NAC \NWC"9;
"S \NAC"
BN"31"47;
%"GND"
"1","(-6125,1075)","0","mstr_symbols","I128";
;
BOM_COST"MEM"
CDS_LIB"mstr_symbols"
SIZE"1B"
VOLTAGE"0.0"
BODY_TYPE"PLUMBING"
HDL_POWER"GND";
"A\NAC"1;
%"Q_RES"
"2","(-6125,1300)","0","pure_quanta","I129";
;
LOCATION"R36"
SEC"1"
MATERIAL"CHIP"
TOLERANCE"1%"
VALUE"10K"
PACK_TYPE"0402LF"
WATTAGE"1/16W"
SEC_TYPE"0402LF"
CDS_LIB"pure_quanta"
BOM_COST"MEM"
PART_NUMBER"CS31002FB08";
"A"
$PN"1"
XNET_PINS"3"46;
"B"
$PN"2"
XNET_PINS"2"1;
%"GND"
"1","(-2100,2075)","0","mstr_symbols","I130";
;
CDS_LIB"mstr_symbols"
SIZE"1B"
VOLTAGE"0.0"
BODY_TYPE"PLUMBING"
HDL_POWER"GND";
"A\NAC"39;
%"GND"
"1","(-500,1875)","0","mstr_symbols","I146";
;
CDS_LIB"mstr_symbols"
SIZE"1B"
VOLTAGE"0.0"
BODY_TYPE"PLUMBING"
HDL_POWER"GND";
"A\NAC"44;
%"SCONN288_DDR506112002KQ"
"3","(-1300,3825)","0","pure_quanta","I177";
;
LOCATION"J24"
$SEC"3"
CDS_SEC"3"
VALUE"SCONN288_DDR506112002KQ"
MATERIAL"IO"
PART_TYPE"SMLF"
CDS_LMAN_SYM_OUTLINE"-450,1800,450,-1750"
NEEDS_NO_SIZE"TRUE"
CDS_LIB"pure_quanta"
PART_NUMBER"DFHST8FS479";
"G3"
$PN"G3"44;
"G2"
$PN"G2"44;
"G1"
$PN"G1"44;
"VSS62"
$PN"141"44;
"VSS61"
$PN"139"44;
"VSS60"
$PN"136"44;
"VSS58"
$PN"132"44;
"VSS104"
$PN"240"39;
"VSS102"
$PN"235"39;
"VSS100"
$PN"230"39;
"VIN_BULK2"
$PN"146"42;
"VIN_BULK1"
$PN"145"42;
"VIN_BULK0"
$PN"1"42;
"VSS126"
$PN"288"39;
"VSS125"
$PN"286"39;
"VSS124"
$PN"284"39;
"VSS123"
$PN"281"39;
"VSS122"
$PN"279"39;
"VSS121"
$PN"277"39;
"VSS120"
$PN"275"39;
"VSS119"
$PN"273"39;
"VSS118"
$PN"270"39;
"VSS117"
$PN"268"39;
"VSS116"
$PN"266"39;
"VSS115"
$PN"264"39;
"VSS114"
$PN"262"39;
"VSS113"
$PN"259"39;
"VSS112"
$PN"257"39;
"VSS111"
$PN"255"39;
"VSS110"
$PN"253"39;
"VSS109"
$PN"251"39;
"VSS108"
$PN"248"39;
"VSS107"
$PN"246"39;
"VSS106"
$PN"244"39;
"VSS105"
$PN"242"39;
"VSS103"
$PN"237"39;
"VSS101"
$PN"233"39;
"VSS99"
$PN"228"39;
"VSS98"
$PN"226"39;
"VSS97"
$PN"224"39;
"VSS96"
$PN"222"39;
"VSS95"
$PN"219"39;
"VSS94"
$PN"216"39;
"VSS93"
$PN"214"39;
"VSS92"
$PN"212"39;
"VSS91"
$PN"210"39;
"VSS90"
$PN"208"39;
"VSS89"
$PN"206"39;
"VSS88"
$PN"204"39;
"VSS87"
$PN"202"39;
"VSS86"
$PN"199"39;
"VSS85"
$PN"197"39;
"VSS84"
$PN"195"39;
"VSS83"
$PN"193"39;
"VSS82"
$PN"191"39;
"VSS81"
$PN"188"39;
"VSS80"
$PN"186"39;
"VSS79"
$PN"184"39;
"VSS78"
$PN"182"39;
"VSS77"
$PN"180"39;
"VSS76"
$PN"177"39;
"VSS75"
$PN"175"39;
"VSS74"
$PN"173"39;
"VSS73"
$PN"171"39;
"VSS72"
$PN"169"39;
"VSS71"
$PN"166"39;
"VSS70"
$PN"164"39;
"VSS69"
$PN"162"39;
"VSS68"
$PN"160"39;
"VSS67"
$PN"158"39;
"VSS66"
$PN"155"39;
"VSS65"
$PN"153"39;
"VSS64"
$PN"151"39;
"VSS63"
$PN"143"44;
"VSS59"
$PN"134"44;
"VSS57"
$PN"130"44;
"VSS56"
$PN"128"44;
"VSS55"
$PN"125"44;
"VSS54"
$PN"123"44;
"VSS53"
$PN"121"44;
"VSS52"
$PN"119"44;
"VSS51"
$PN"117"44;
"VSS50"
$PN"114"44;
"VSS49"
$PN"112"44;
"VSS48"
$PN"110"44;
"VSS47"
$PN"108"44;
"VSS46"
$PN"106"44;
"VSS45"
$PN"103"44;
"VSS44"
$PN"101"44;
"VSS43"
$PN"99"44;
"VSS42"
$PN"97"44;
"VSS41"
$PN"95"44;
"VSS40"
$PN"92"44;
"VSS39"
$PN"90"44;
"VSS38"
$PN"88"44;
"VSS37"
$PN"85"44;
"VSS36"
$PN"83"44;
"VSS35"
$PN"81"44;
"VSS34"
$PN"79"44;
"VSS33"
$PN"77"44;
"VSS32"
$PN"75"44;
"VSS31"
$PN"73"44;
"VSS30"
$PN"71"44;
"VSS29"
$PN"69"44;
"VSS28"
$PN"67"44;
"VSS27"
$PN"65"44;
"VSS26"
$PN"63"44;
"VSS25"
$PN"61"44;
"VSS24"
$PN"59"44;
"VSS23"
$PN"57"44;
"VSS22"
$PN"54"44;
"VSS21"
$PN"52"44;
"VSS20"
$PN"50"44;
"VSS19"
$PN"48"44;
"VSS18"
$PN"46"44;
"VSS17"
$PN"43"44;
"VSS16"
$PN"41"44;
"VSS15"
$PN"39"44;
"VSS14"
$PN"37"44;
"VSS13"
$PN"35"44;
"VSS12"
$PN"32"44;
"VSS11"
$PN"30"44;
"VSS10"
$PN"28"44;
"VSS9"
$PN"26"44;
"VSS8"
$PN"24"44;
"VSS7"
$PN"21"44;
"VSS6"
$PN"19"44;
"VSS5"
$PN"17"44;
"VSS4"
$PN"15"44;
"VSS3"
$PN"13"44;
"VSS2"
$PN"10"44;
"VSS1"
$PN"8"44;
"VSS0"
$PN"6"44;
%"Q_CAP"
"1","(-8600,3325)","2","pure_quanta","I185";
;
LOCATION"C136"
$SEC"1"
CDS_SEC"1"
PACK_TYPE"0402"
VOLTAGE"25V"
VALUE"0.1UF"
TOLERANCE"10%"
MATERIAL"X7R"
BOM_COST"MEM"
CDS_LIB"pure_quanta"
ROOM""
PART_NUMBER"CH4104K1B00";
"B"
$PN"2"2;
"A"
$PN"1"22;
%"GND"
"1","(-8600,3100)","0","mstr_symbols","I186";
;
CDS_LIB"mstr_symbols"
SIZE"1B"
BOM_COST"MEM"
VOLTAGE"0"
ROOM"MEM_EFGH_DECOUPLING_CAPS"
BODY_TYPE"PLUMBING"
HDL_POWER"GND";
"A\NAC"2;
%"VCC_CORE"
"1","(-8525,2550)","0","mstr_symbols","I188";
;
HDL_POWER"P3V3"
CDS_LIB"mstr_symbols"
VOLTAGE"3.3"
ROOM"PVCCINFAON_CPU0_CTRL";
"A"3;
%"Q_RES"
"2","(-8525,2375)","2","pure_quanta","I189";
;
LOCATION"R102"
$SEC"1"
CDS_SEC"1"
TOLERANCE"1%"
WATTAGE"1/16W"
VALUE"1K"
PACK_TYPE"0402LF"
MATERIAL"EMPTY"
BOM_COST"MEM"
CDS_LIB"pure_quanta"
ROOM""
PART_NUMBER"CS21002FB06";
"A"
$PN"1"3;
"B"
$PN"2"180;
%"Q_RES"
"1","(-8400,2225)","2","pure_quanta","I190";
;
LOCATION"R303"
$SEC"1"
CDS_SEC"1"
VALUE"1K"
TOLERANCE"1%"
CDS_LIB"pure_quanta"
BOM_COST"MEM"
WATTAGE"1/16W"
MATERIAL"CHIP"
PACK_TYPE"0402LF"
ROOM""
PART_NUMBER"CS21002FB06";
"B"
$PN"2"180;
"A"
$PN"1"20;
%"Q_RES"
"2","(-8275,2375)","0","pure_quanta","I191";
;
LOCATION"R103"
$SEC"1"
CDS_SEC"1"
VALUE"1K"
PACK_TYPE"0402LF"
MATERIAL"EMPTY"
WATTAGE"1/16W"
TOLERANCE"1%"
BOM_COST"MEM"
CDS_LIB"pure_quanta"
ROOM""
PART_NUMBER"CS21002FB06";
"A"
$PN"1"4;
"B"
$PN"2"20;
%"VCC_CORE"
"1","(-8275,2550)","0","mstr_symbols","I192";
;
HDL_POWER"P3V3"
CDS_LIB"mstr_symbols"
VOLTAGE"3.3"
ROOM"PVCCINFAON_CPU0_CTRL";
"A"4;
%"TAP"
"1","(-3025,4550)","0","mstr_standard","I198";
;
CDS_LIB"mstr_standard"
BODY_TYPE"PLUMBING"
HDL_TAP"TRUE";
"B \NAC \NWC"12;
"S \NAC"
BN"9"167;
%"TAP"
"1","(-3025,4450)","0","mstr_standard","I199";
;
CDS_LIB"mstr_standard"
BODY_TYPE"PLUMBING"
HDL_TAP"TRUE";
"B \NAC \NWC"12;
"S \NAC"
BN"8"165;
%"TAP"
"1","(-3025,4350)","0","mstr_standard","I200";
;
CDS_LIB"mstr_standard"
BODY_TYPE"PLUMBING"
HDL_TAP"TRUE";
"B \NAC \NWC"12;
"S \NAC"
BN"7"131;
%"TAP"
"1","(-3225,4600)","0","mstr_standard","I201";
;
CDS_LIB"mstr_standard"
BODY_TYPE"PLUMBING"
HDL_TAP"TRUE";
"B \NAC \NWC"8;
"S \NAC"
BN"9"172;
%"TAP"
"1","(-3225,4500)","0","mstr_standard","I202";
;
CDS_LIB"mstr_standard"
BODY_TYPE"PLUMBING"
HDL_TAP"TRUE";
"B \NAC \NWC"8;
"S \NAC"
BN"8"166;
%"TAP"
"1","(-3225,4400)","0","mstr_standard","I203";
;
CDS_LIB"mstr_standard"
BODY_TYPE"PLUMBING"
HDL_TAP"TRUE";
"B \NAC \NWC"8;
"S \NAC"
BN"7"163;
%"TAP"
"1","(-3025,4250)","0","mstr_standard","I204";
;
CDS_LIB"mstr_standard"
BODY_TYPE"PLUMBING"
HDL_TAP"TRUE";
"B \NAC \NWC"12;
"S \NAC"
BN"6"160;
%"TAP"
"1","(-3025,4150)","0","mstr_standard","I205";
;
CDS_LIB"mstr_standard"
BODY_TYPE"PLUMBING"
HDL_TAP"TRUE";
"B \NAC \NWC"12;
"S \NAC"
BN"5"156;
%"TAP"
"1","(-3025,3950)","0","mstr_standard","I206";
;
CDS_LIB"mstr_standard"
BODY_TYPE"PLUMBING"
HDL_TAP"TRUE";
"B \NAC \NWC"12;
"S \NAC"
BN"3"148;
%"TAP"
"1","(-3025,4050)","0","mstr_standard","I207";
;
CDS_LIB"mstr_standard"
BODY_TYPE"PLUMBING"
HDL_TAP"TRUE";
"B \NAC \NWC"12;
"S \NAC"
BN"4"152;
%"TAP"
"1","(-3025,3850)","0","mstr_standard","I208";
;
CDS_LIB"mstr_standard"
BODY_TYPE"PLUMBING"
HDL_TAP"TRUE";
"B \NAC \NWC"12;
"S \NAC"
BN"2"144;
%"TAP"
"1","(-3225,4100)","0","mstr_standard","I209";
;
CDS_LIB"mstr_standard"
BODY_TYPE"PLUMBING"
HDL_TAP"TRUE";
"B \NAC \NWC"8;
"S \NAC"
BN"4"153;
%"TAP"
"1","(-3225,4200)","0","mstr_standard","I210";
;
CDS_LIB"mstr_standard"
BODY_TYPE"PLUMBING"
HDL_TAP"TRUE";
"B \NAC \NWC"8;
"S \NAC"
BN"5"157;
%"TAP"
"1","(-3225,4300)","0","mstr_standard","I211";
;
CDS_LIB"mstr_standard"
BODY_TYPE"PLUMBING"
HDL_TAP"TRUE";
"B \NAC \NWC"8;
"S \NAC"
BN"6"132;
%"TAP"
"1","(-3225,4000)","0","mstr_standard","I212";
;
CDS_LIB"mstr_standard"
BODY_TYPE"PLUMBING"
HDL_TAP"TRUE";
"B \NAC \NWC"8;
"S \NAC"
BN"3"149;
%"TAP"
"1","(-3225,3900)","0","mstr_standard","I213";
;
CDS_LIB"mstr_standard"
BODY_TYPE"PLUMBING"
HDL_TAP"TRUE";
"B \NAC \NWC"8;
"S \NAC"
BN"2"145;
%"TAP"
"1","(-3025,3750)","0","mstr_standard","I214";
;
CDS_LIB"mstr_standard"
BODY_TYPE"PLUMBING"
HDL_TAP"TRUE";
"B \NAC \NWC"12;
"S \NAC"
BN"1"140;
%"TAP"
"1","(-3025,3650)","0","mstr_standard","I215";
;
CDS_LIB"mstr_standard"
BODY_TYPE"PLUMBING"
HDL_TAP"TRUE";
"B \NAC \NWC"12;
"S \NAC"
BN"0"136;
%"TAP"
"1","(-3025,3500)","0","mstr_standard","I216";
;
CDS_LIB"mstr_standard"
BODY_TYPE"PLUMBING"
HDL_TAP"TRUE";
"B \NAC \NWC"11;
"S \NAC"
BN"9"168;
%"TAP"
"1","(-3025,3400)","0","mstr_standard","I217";
;
CDS_LIB"mstr_standard"
BODY_TYPE"PLUMBING"
HDL_TAP"TRUE";
"B \NAC \NWC"11;
"S \NAC"
BN"8"134;
%"TAP"
"1","(-3025,3300)","0","mstr_standard","I218";
;
CDS_LIB"mstr_standard"
BODY_TYPE"PLUMBING"
HDL_TAP"TRUE";
"B \NAC \NWC"11;
"S \NAC"
BN"7"164;
%"TAP"
"1","(-3225,3700)","0","mstr_standard","I219";
;
CDS_LIB"mstr_standard"
BODY_TYPE"PLUMBING"
HDL_TAP"TRUE";
"B \NAC \NWC"8;
"S \NAC"
BN"0"137;
%"SCONN288_DDR506112002KQ"
"1","(-6600,3725)","0","pure_quanta","I22";
;
LOCATION"J24"
$SEC"1"
CDS_SEC"1"
VALUE"SCONN288_DDR506112002KQ"
PART_TYPE"SMLF"
MATERIAL"IO"
CDS_LMAN_SYM_OUTLINE"-450,1900,450,-1850"
NEEDS_NO_SIZE"TRUE"
CDS_LIB"pure_quanta"
PART_NUMBER"DFHST8FS479";
"PWR_GOOD||FAIL_N"
$PN"147"20;
"DQ31_A"
$PN"194"47;
"CB7_A"
$PN"205"48;
"CB4_A"
$PN"58"49;
"CB1_A"
$PN"53"28;
"CB7_B"
$PN"236"26;
"ALERT_N \B"
$PN"62"23;
"CA0_A"
$PN"66"127;
"CA0_B"
$PN"76"50;
"CA1_A"
$PN"211"173;
"CA1_B"
$PN"221"51;
"CA2_A"
$PN"68"52;
"CA2_B"
$PN"78"53;
"CA3_A"
$PN"213"174;
"CA3_B"
$PN"223"54;
"CA4_A"
$PN"70"55;
"CA4_B"
$PN"80"56;
"CA5_A"
$PN"215"57;
"CA5_B"
$PN"225"58;
"CA6_A"
$PN"72"175;
"CA6_B"
$PN"82"59;
"CB6_A"
$PN"203"60;
"CB5_A"
$PN"60"61;
"CB3_A"
$PN"198"62;
"CB2_A"
$PN"196"63;
"CB0_A"
$PN"51"27;
"CB6_B"
$PN"234"32;
"CB5_B"
$PN"91"31;
"CB4_B"
$PN"89"30;
"CB3_B"
$PN"243"29;
"CB2_B"
$PN"241"64;
"CB1_B"
$PN"98"65;
"CB0_B"
$PN"96"66;
"CK_C \B"
$PN"218"67;
"CK_T"
$PN"217"68;
"CS0_A_N"
$PN"64"35;
"CS0_B_N"
$PN"84"69;
"CS1_A_N"
$PN"209"70;
"CS1_B_N"
$PN"229"71;
"DQ30_A"
$PN"192"72;
"DQ29_A"
$PN"49"73;
"DQ28_A"
$PN"47"125;
"DQ27_A"
$PN"187"126;
"DQ26_A"
$PN"185"74;
"DQ25_A"
$PN"42"75;
"DQ24_A"
$PN"40"128;
"DQ23_A"
$PN"183"76;
"DQ22_A"
$PN"181"170;
"DQ21_A"
$PN"38"171;
"DQ20_A"
$PN"36"77;
"DQ19_A"
$PN"176"78;
"DQ18_A"
$PN"174"129;
"DQ17_A"
$PN"31"130;
"DQ16_A"
$PN"29"79;
"DQ15_A"
$PN"172"80;
"DQ14_A"
$PN"170"81;
"DQ13_A"
$PN"27"82;
"DQ12_A"
$PN"25"83;
"DQ11_A"
$PN"165"84;
"DQ10_A"
$PN"163"85;
"DQ9_A"
$PN"20"86;
"DQ8_A"
$PN"18"87;
"DQ7_A"
$PN"161"88;
"DQ6_A"
$PN"159"89;
"DQ5_A"
$PN"16"90;
"DQ4_A"
$PN"14"91;
"DQ3_A"
$PN"154"92;
"DQ2_A"
$PN"152"93;
"DQ1_A"
$PN"9"94;
"DQ0_A"
$PN"7"95;
"DQ31_B"
$PN"287"96;
"DQ30_B"
$PN"285"33;
"DQ29_B"
$PN"142"34;
"DQ28_B"
$PN"140"97;
"DQ27_B"
$PN"280"98;
"DQ26_B"
$PN"278"99;
"DQ25_B"
$PN"135"100;
"DQ24_B"
$PN"133"101;
"DQ23_B"
$PN"276"102;
"DQ22_B"
$PN"274"103;
"DQ21_B"
$PN"131"176;
"DQ20_B"
$PN"129"104;
"DQ19_B"
$PN"269"105;
"DQ18_B"
$PN"267"106;
"DQ17_B"
$PN"124"107;
"DQ16_B"
$PN"122"108;
"DQ15_B"
$PN"265"109;
"DQ14_B"
$PN"263"110;
"DQ13_B"
$PN"120"111;
"DQ12_B"
$PN"118"112;
"DQ11_B"
$PN"258"113;
"DQ10_B"
$PN"256"114;
"DQ9_B"
$PN"113"115;
"DQ8_B"
$PN"111"116;
"DQ7_B"
$PN"254"117;
"DQ6_B"
$PN"252"178;
"DQ5_B"
$PN"109"177;
"DQ4_B"
$PN"107"179;
"DQ3_B"
$PN"247"118;
"DQ2_B"
$PN"245"119;
"DQ1_B"
$PN"102"120;
"DQ0_B"
$PN"100"121;
"HAS"
$PN"148"21;
"HSCL"
$PN"4"24;
"HSDA"
$PN"5"18;
"LBD||RSP_A_N"
$PN"86"122;
"LBS||RSP_B_N"
$PN"87"16;
"PAR_A"
$PN"74"123;
"PAR_B"
$PN"227"124;
"RESET_N \B"
$PN"207"25;
"RFU6"
$PN"232"0;
"RFU5"
$PN"231"0;
"RFU4"
$PN"220"0;
"RFU3"
$PN"150"0;
"RFU2"
$PN"149"0;
"RFU1"
$PN"144"0;
"RFU0"
$PN"2"0;
"VIN_MGMT"
$PN"3"22;
%"TAP"
"1","(-3225,3800)","0","mstr_standard","I220";
;
CDS_LIB"mstr_standard"
BODY_TYPE"PLUMBING"
HDL_TAP"TRUE";
"B \NAC \NWC"8;
"S \NAC"
BN"1"141;
%"TAP"
"1","(-3225,3550)","0","mstr_standard","I221";
;
CDS_LIB"mstr_standard"
BODY_TYPE"PLUMBING"
HDL_TAP"TRUE";
"B \NAC \NWC"10;
"S \NAC"
BN"9"169;
%"TAP"
"1","(-3225,3450)","0","mstr_standard","I222";
;
CDS_LIB"mstr_standard"
BODY_TYPE"PLUMBING"
HDL_TAP"TRUE";
"B \NAC \NWC"10;
"S \NAC"
BN"8"133;
%"TAP"
"1","(-3225,3350)","0","mstr_standard","I223";
;
CDS_LIB"mstr_standard"
BODY_TYPE"PLUMBING"
HDL_TAP"TRUE";
"B \NAC \NWC"10;
"S \NAC"
BN"7"135;
%"TAP"
"1","(-3025,3200)","0","mstr_standard","I224";
;
CDS_LIB"mstr_standard"
BODY_TYPE"PLUMBING"
HDL_TAP"TRUE";
"B \NAC \NWC"11;
"S \NAC"
BN"6"161;
%"TAP"
"1","(-3025,3100)","0","mstr_standard","I225";
;
CDS_LIB"mstr_standard"
BODY_TYPE"PLUMBING"
HDL_TAP"TRUE";
"B \NAC \NWC"11;
"S \NAC"
BN"5"158;
%"TAP"
"1","(-3025,3000)","0","mstr_standard","I226";
;
CDS_LIB"mstr_standard"
BODY_TYPE"PLUMBING"
HDL_TAP"TRUE";
"B \NAC \NWC"11;
"S \NAC"
BN"4"154;
%"TAP"
"1","(-3025,2800)","0","mstr_standard","I227";
;
CDS_LIB"mstr_standard"
BODY_TYPE"PLUMBING"
HDL_TAP"TRUE";
"B \NAC \NWC"11;
"S \NAC"
BN"2"146;
%"TAP"
"1","(-3025,2900)","0","mstr_standard","I228";
;
CDS_LIB"mstr_standard"
BODY_TYPE"PLUMBING"
HDL_TAP"TRUE";
"B \NAC \NWC"11;
"S \NAC"
BN"3"150;
%"TAP"
"1","(-3225,3250)","0","mstr_standard","I229";
;
CDS_LIB"mstr_standard"
BODY_TYPE"PLUMBING"
HDL_TAP"TRUE";
"B \NAC \NWC"10;
"S \NAC"
BN"6"162;
%"TAP"
"1","(-7450,3275)","2","mstr_standard","I23";
;
CDS_LIB"mstr_standard"
BODY_TYPE"PLUMBING"
HDL_TAP"TRUE";
"B \NAC \NWC"13;
"S \NAC"
BN"0"66;
%"TAP"
"1","(-3225,3050)","0","mstr_standard","I230";
;
CDS_LIB"mstr_standard"
BODY_TYPE"PLUMBING"
HDL_TAP"TRUE";
"B \NAC \NWC"10;
"S \NAC"
BN"4"155;
%"TAP"
"1","(-3225,3150)","0","mstr_standard","I231";
;
CDS_LIB"mstr_standard"
BODY_TYPE"PLUMBING"
HDL_TAP"TRUE";
"B \NAC \NWC"10;
"S \NAC"
BN"5"159;
%"TAP"
"1","(-3225,2950)","0","mstr_standard","I232";
;
CDS_LIB"mstr_standard"
BODY_TYPE"PLUMBING"
HDL_TAP"TRUE";
"B \NAC \NWC"10;
"S \NAC"
BN"3"151;
%"TAP"
"1","(-3225,2850)","0","mstr_standard","I233";
;
CDS_LIB"mstr_standard"
BODY_TYPE"PLUMBING"
HDL_TAP"TRUE";
"B \NAC \NWC"10;
"S \NAC"
BN"2"147;
%"TAP"
"1","(-3025,2700)","0","mstr_standard","I234";
;
CDS_LIB"mstr_standard"
BODY_TYPE"PLUMBING"
HDL_TAP"TRUE";
"B \NAC \NWC"11;
"S \NAC"
BN"1"142;
%"TAP"
"1","(-3025,2600)","0","mstr_standard","I235";
;
CDS_LIB"mstr_standard"
BODY_TYPE"PLUMBING"
HDL_TAP"TRUE";
"B \NAC \NWC"11;
"S \NAC"
BN"0"138;
%"TAP"
"1","(-3225,2650)","0","mstr_standard","I236";
;
CDS_LIB"mstr_standard"
BODY_TYPE"PLUMBING"
HDL_TAP"TRUE";
"B \NAC \NWC"10;
"S \NAC"
BN"0"139;
%"TAP"
"1","(-3225,2750)","0","mstr_standard","I237";
;
CDS_LIB"mstr_standard"
BODY_TYPE"PLUMBING"
HDL_TAP"TRUE";
"B \NAC \NWC"10;
"S \NAC"
BN"1"143;
%"SCONN288_DDR506112002KQ"
"2","(-4225,3600)","0","pure_quanta","I238";
;
LOCATION"J24"
$SEC"2"
CDS_SEC"2"
PART_TYPE"SMLF"
MATERIAL"IO"
VALUE"SCONN288_DDR506112002KQ"
CDS_LMAN_SYM_OUTLINE"-600,1150,600,-1150"
NEEDS_NO_SIZE"TRUE"
CDS_LIB"pure_quanta"
PART_NUMBER"DFHST8FS479";
"DQS7_A_C||TDQS7_A_C \B"
$PN"178"131;
"DQS6_A_T||TDQS6_A_T"
$PN"168"132;
"DQS8_B_T||TDQS8_B_T"
$PN"283"133;
"DQS8_B_C||TDQS8_B_C \B"
$PN"282"134;
"DQS7_B_T||TDQS7_B_T"
$PN"272"135;
"DQS0_A_C \B"
$PN"12"136;
"DQS0_A_T"
$PN"11"137;
"DQS0_B_C \B"
$PN"105"138;
"DQS0_B_T"
$PN"104"139;
"DQS1_A_C \B"
$PN"23"140;
"DQS1_A_T"
$PN"22"141;
"DQS1_B_C \B"
$PN"116"142;
"DQS1_B_T"
$PN"115"143;
"DQS2_A_C \B"
$PN"34"144;
"DQS2_A_T"
$PN"33"145;
"DQS2_B_C \B"
$PN"127"146;
"DQS2_B_T"
$PN"126"147;
"DQS3_A_C \B"
$PN"45"148;
"DQS3_A_T"
$PN"44"149;
"DQS3_B_C \B"
$PN"138"150;
"DQS3_B_T"
$PN"137"151;
"DQS4_A_C \B"
$PN"56"152;
"DQS4_A_T"
$PN"55"153;
"DQS4_B_C \B"
$PN"238"154;
"DQS4_B_T"
$PN"239"155;
"DQS5_A_C||TDQS5_A_C||DQS5_A_T||TDQS5_A_T \B"
$PN"156"156;
"DQS5_A_T||TDQS5_A_T"
$PN"157"157;
"DQS5_B_C||TDQS5_B_C \B"
$PN"249"158;
"DQS5_B_T||TDQS5_B_T"
$PN"250"159;
"DQS6_A_C||TDQS6_A_C||DQS6_A_T||TDQS6_A_T \B"
$PN"167"160;
"DQS6_B_C||TDQS6_B_C \B"
$PN"260"161;
"DQS6_B_T||TDQS6_B_T"
$PN"261"162;
"DQS7_A_T||TDQS7_A_T"
$PN"179"163;
"DQS7_B_C||TDQS7_B_C \B"
$PN"271"164;
"DQS8_A_C||TDQS8_A_C \B"
$PN"189"165;
"DQS8_A_T||TDQS8_A_T"
$PN"190"166;
"DQS9_A_C||TDQS9_A_C \B"
$PN"200"167;
"DQS9_A_T||TDQS9_A_T"
$PN"201"172;
"DQS9_B_C||TDQS9_B_C \B"
$PN"94"168;
"DQS9_B_T||TDQS9_B_T||DBI4_B_N"
$PN"93"169;
%"GND"
"1","(-2800,5750)","0","pure_quanta_power","I239";
;
CDS_LIB"pure_quanta_power"
BOM_COST"MEM"
SIZE"1B"
ROOM"MEM_EFGH_DECOUPLING_CAPS"
HDL_POWER"GND";
"A<SIZE-1..0>\NAC"43;
%"TAP"
"1","(-7450,3325)","2","mstr_standard","I24";
;
CDS_LIB"mstr_standard"
BODY_TYPE"PLUMBING"
HDL_TAP"TRUE";
"B \NAC \NWC"13;
"S \NAC"
BN"1"65;
%"Q_CAP"
"1","(-2800,6100)","2","pure_quanta","I240";
;
LOCATION"C173"
$SEC"1"
CDS_SEC"1"
PACK_TYPE"C0805"
VOLTAGE"25V"
VALUE"10UF"
TOLERANCE"10%"
MATERIAL"X6S"
CDS_LIB"pure_quanta"
BOM_COST"MEM"
ROOM""
PART_NUMBER"CH6104KEA00";
"B"
$PN"2"43;
"A"
$PN"1"42;
%"Q_CAP"
"1","(-2225,6100)","2","pure_quanta","I241";
;
LOCATION"C174"
$SEC"1"
CDS_SEC"1"
PACK_TYPE"C0805"
VOLTAGE"25V"
VALUE"10UF"
TOLERANCE"10%"
MATERIAL"X6S"
CDS_LIB"pure_quanta"
BOM_COST"MEM"
ROOM""
PART_NUMBER"CH6104KEA00";
"B"
$PN"2"43;
"A"
$PN"1"42;
%"UNIVERSAL_POWER"
"1","(-2800,6425)","0","pure_quanta_power","I242";
;
HDL_POWER"P12V_MEM_CPU1"
CDS_LIB"pure_quanta_power";
"A"42;
%"Q_RES"
"1","(-7475,2725)","0","pure_quanta","I244";
;
LOCATION"R1580"
$SEC"1"
CDS_SEC"1"
VALUE"49.9"
CDS_LIB"pure_quanta"
TOLERANCE"1%"
WATTAGE"1/16W"
PACK_TYPE"0402LF"
MATERIAL"CHIP"
PART_NUMBER"CS04992FB07";
"B"
$PN"2"24;
"A"
$PN"1"19;
%"Q_RES"
"2","(-8950,1450)","0","pure_quanta","I245";
;
LOCATION"R8039"
$SEC"1"
CDS_SEC"1"
TOLERANCE"1%"
WATTAGE"1/16W"
VALUE"10K"
MATERIAL"CHIP"
PACK_TYPE"0402LF"
CDS_LIB"pure_quanta"
PART_NUMBER"CS31002FB08";
"A"
$PN"1"5;
"B"
$PN"2"37;
%"VCC_CORE"
"1","(-8950,1750)","0","pure_quanta_power","I246";
;
HDL_POWER"P3V3_AUX"
CDS_LIB"pure_quanta_power"
ROOM"PVCCINFAON_CPU0_CTRL"
VOLTAGE"3.3";
"A"5;
%"VCC_CORE"
"1","(-5025,1600)","0","pure_quanta_power","I249";
;
HDL_POWER"P3V3_AUX"
CDS_LIB"pure_quanta_power"
ROOM"PVCCINFAON_CPU0_CTRL"
VOLTAGE"3.3";
"A"41;
%"TAP"
"1","(-7450,3375)","2","mstr_standard","I25";
;
CDS_LIB"mstr_standard"
BODY_TYPE"PLUMBING"
HDL_TAP"TRUE";
"B \NAC \NWC"13;
"S \NAC"
BN"2"64;
%"Q_RES"
"1","(-4000,925)","0","pure_quanta","I250";
;
LOCATION"R8086"
$SEC"1"
CDS_SEC"1"
VALUE"0"
TOLERANCE"5%"
MATERIAL"CHIP"
PACK_TYPE"0402LF"
WATTAGE"1/16W"
CDS_LIB"pure_quanta"
PART_NUMBER"CS00002JB13";
"B"
$PN"2"36;
"A"
$PN"1"38;
%"Q_RES"
"1","(-4425,1400)","0","pure_quanta","I251";
;
LOCATION"R8088"
$SEC"1"
CDS_SEC"1"
MATERIAL"EMPTY"
PACK_TYPE"0402LF"
WATTAGE"1/16W"
VALUE"10K"
TOLERANCE"1%"
CDS_LIB"pure_quanta"
PART_NUMBER"CS31002FB08";
"B"
$PN"2"36;
"A"
$PN"1"41;
%"Q_RES"
"1","(-2575,925)","0","pure_quanta","I252";
;
LOCATION"R8087"
$SEC"1"
CDS_SEC"1"
WATTAGE"1/16W"
MATERIAL"CHIP"
PACK_TYPE"0402LF"
TOLERANCE"5%"
VALUE"0"
CDS_LIB"pure_quanta"
PART_NUMBER"CS00002JB13";
"B"
$PN"2"45;
"A"
$PN"1"36;
%"SCHOTTKY_12"
"1","(-2475,1375)","0","pure_quanta","I253";
;
LOCATION"D8005"
$SEC"1"
CDS_SEC"1"
MATERIAL"EMPTY"
VALUE"B0530WS7F"
PART_TYPE"SMLF"
CDS_LIB"pure_quanta"
CDS_LMAN_SYM_OUTLINE"-75,50,75,-50"
NEEDS_NO_SIZE"TRUE"
PART_NUMBER"BC000530Z41";
"C"
$PN"2"40;
"A"
$PN"1"36;
%"VCC_CORE"
"1","(-1800,1500)","0","pure_quanta_power","I254";
;
HDL_POWER"P3V3_AUX"
CDS_LIB"pure_quanta_power"
VOLTAGE"3.3"
ROOM"PVCCINFAON_CPU0_CTRL";
"A"40;
%"Q_RES"
"1","(-7875,2925)","0","pure_quanta","I256";
;
LOCATION"R1687"
$SEC"1"
CDS_SEC"1"
MATERIAL"CHIP"
VALUE"10"
PACK_TYPE"0402LF"
WATTAGE"1/16W"
TOLERANCE"1%"
CDS_LIB"pure_quanta"
PART_NUMBER"CS01002FB07";
"B"
$PN"2"18;
"A"
$PN"1"17;
%"TAP"
"1","(-7450,3425)","2","mstr_standard","I26";
;
CDS_LIB"mstr_standard"
BODY_TYPE"PLUMBING"
HDL_TAP"TRUE";
"B \NAC \NWC"13;
"S \NAC"
BN"3"29;
%"TAP"
"1","(-7450,3475)","2","mstr_standard","I27";
;
CDS_LIB"mstr_standard"
BODY_TYPE"PLUMBING"
HDL_TAP"TRUE";
"B \NAC \NWC"13;
"S \NAC"
BN"4"30;
%"TAP"
"1","(-7450,3525)","2","mstr_standard","I28";
;
CDS_LIB"mstr_standard"
BODY_TYPE"PLUMBING"
HDL_TAP"TRUE";
"B \NAC \NWC"13;
"S \NAC"
BN"5"31;
%"TAP"
"1","(-7450,3575)","2","mstr_standard","I29";
;
CDS_LIB"mstr_standard"
BODY_TYPE"PLUMBING"
HDL_TAP"TRUE";
"B \NAC \NWC"13;
"S \NAC"
BN"6"32;
%"TAP"
"1","(-7450,3625)","2","mstr_standard","I30";
;
CDS_LIB"mstr_standard"
BODY_TYPE"PLUMBING"
HDL_TAP"TRUE";
"B \NAC \NWC"13;
"S \NAC"
BN"7"26;
%"TAP"
"1","(-7450,3725)","2","mstr_standard","I31";
;
CDS_LIB"mstr_standard"
BODY_TYPE"PLUMBING"
HDL_TAP"TRUE";
"B \NAC \NWC"14;
"S \NAC"
BN"0"27;
%"TAP"
"1","(-7450,3775)","2","mstr_standard","I32";
;
CDS_LIB"mstr_standard"
BODY_TYPE"PLUMBING"
HDL_TAP"TRUE";
"B \NAC \NWC"14;
"S \NAC"
BN"1"28;
%"TAP"
"1","(-7450,3825)","2","mstr_standard","I33";
;
CDS_LIB"mstr_standard"
BODY_TYPE"PLUMBING"
HDL_TAP"TRUE";
"B \NAC \NWC"14;
"S \NAC"
BN"2"63;
%"TAP"
"1","(-7450,3875)","2","mstr_standard","I34";
;
CDS_LIB"mstr_standard"
BODY_TYPE"PLUMBING"
HDL_TAP"TRUE";
"B \NAC \NWC"14;
"S \NAC"
BN"3"62;
%"TAP"
"1","(-7450,3925)","2","mstr_standard","I35";
;
CDS_LIB"mstr_standard"
BODY_TYPE"PLUMBING"
HDL_TAP"TRUE";
"B \NAC \NWC"14;
"S \NAC"
BN"4"49;
%"TAP"
"1","(-7450,3975)","2","mstr_standard","I36";
;
CDS_LIB"mstr_standard"
BODY_TYPE"PLUMBING"
HDL_TAP"TRUE";
"B \NAC \NWC"14;
"S \NAC"
BN"5"61;
%"TAP"
"1","(-7450,4025)","2","mstr_standard","I37";
;
CDS_LIB"mstr_standard"
BODY_TYPE"PLUMBING"
HDL_TAP"TRUE";
"B \NAC \NWC"14;
"S \NAC"
BN"6"60;
%"TAP"
"1","(-7450,4075)","2","mstr_standard","I38";
;
CDS_LIB"mstr_standard"
BODY_TYPE"PLUMBING"
HDL_TAP"TRUE";
"B \NAC \NWC"14;
"S \NAC"
BN"7"48;
%"TAP"
"1","(-5750,2325)","0","mstr_standard","I46";
;
CDS_LIB"mstr_standard"
BODY_TYPE"PLUMBING"
HDL_TAP"TRUE";
"B \NAC \NWC"6;
"S \NAC"
BN"1"120;
%"TAP"
"1","(-5750,2275)","0","mstr_standard","I47";
;
CDS_LIB"mstr_standard"
BODY_TYPE"PLUMBING"
HDL_TAP"TRUE";
"B \NAC \NWC"6;
"S \NAC"
BN"0"121;
%"TAP"
"1","(-5750,2475)","0","mstr_standard","I48";
;
CDS_LIB"mstr_standard"
BODY_TYPE"PLUMBING"
HDL_TAP"TRUE";
"B \NAC \NWC"6;
"S \NAC"
BN"4"179;
%"TAP"
"1","(-5750,2425)","0","mstr_standard","I49";
;
CDS_LIB"mstr_standard"
BODY_TYPE"PLUMBING"
HDL_TAP"TRUE";
"B \NAC \NWC"6;
"S \NAC"
BN"3"118;
%"TAP"
"1","(-5750,2375)","0","mstr_standard","I50";
;
CDS_LIB"mstr_standard"
BODY_TYPE"PLUMBING"
HDL_TAP"TRUE";
"B \NAC \NWC"6;
"S \NAC"
BN"2"119;
%"TAP"
"1","(-5750,2525)","0","mstr_standard","I51";
;
CDS_LIB"mstr_standard"
BODY_TYPE"PLUMBING"
HDL_TAP"TRUE";
"B \NAC \NWC"6;
"S \NAC"
BN"5"177;
%"TAP"
"1","(-5750,2575)","0","mstr_standard","I52";
;
CDS_LIB"mstr_standard"
BODY_TYPE"PLUMBING"
HDL_TAP"TRUE";
"B \NAC \NWC"6;
"S \NAC"
BN"6"178;
%"TAP"
"1","(-5750,2725)","0","mstr_standard","I53";
;
CDS_LIB"mstr_standard"
BODY_TYPE"PLUMBING"
HDL_TAP"TRUE";
"B \NAC \NWC"6;
"S \NAC"
BN"9"115;
%"TAP"
"1","(-5750,2675)","0","mstr_standard","I54";
;
CDS_LIB"mstr_standard"
BODY_TYPE"PLUMBING"
HDL_TAP"TRUE";
"B \NAC \NWC"6;
"S \NAC"
BN"8"116;
%"TAP"
"1","(-5750,2625)","0","mstr_standard","I55";
;
CDS_LIB"mstr_standard"
BODY_TYPE"PLUMBING"
HDL_TAP"TRUE";
"B \NAC \NWC"6;
"S \NAC"
BN"7"117;
%"TAP"
"1","(-5750,2775)","0","mstr_standard","I56";
;
CDS_LIB"mstr_standard"
BODY_TYPE"PLUMBING"
HDL_TAP"TRUE";
"B \NAC \NWC"6;
"S \NAC"
BN"10"114;
%"TAP"
"1","(-5750,2825)","0","mstr_standard","I57";
;
CDS_LIB"mstr_standard"
BODY_TYPE"PLUMBING"
HDL_TAP"TRUE";
"B \NAC \NWC"6;
"S \NAC"
BN"11"113;
%"TAP"
"1","(-5750,2975)","0","mstr_standard","I58";
;
CDS_LIB"mstr_standard"
BODY_TYPE"PLUMBING"
HDL_TAP"TRUE";
"B \NAC \NWC"6;
"S \NAC"
BN"14"110;
%"TAP"
"1","(-5750,2925)","0","mstr_standard","I59";
;
CDS_LIB"mstr_standard"
BODY_TYPE"PLUMBING"
HDL_TAP"TRUE";
"B \NAC \NWC"6;
"S \NAC"
BN"13"111;
%"TAP"
"1","(-5750,2875)","0","mstr_standard","I60";
;
CDS_LIB"mstr_standard"
BODY_TYPE"PLUMBING"
HDL_TAP"TRUE";
"B \NAC \NWC"6;
"S \NAC"
BN"12"112;
%"TAP"
"1","(-5750,3075)","0","mstr_standard","I61";
;
CDS_LIB"mstr_standard"
BODY_TYPE"PLUMBING"
HDL_TAP"TRUE";
"B \NAC \NWC"6;
"S \NAC"
BN"16"108;
%"TAP"
"1","(-5750,3025)","0","mstr_standard","I62";
;
CDS_LIB"mstr_standard"
BODY_TYPE"PLUMBING"
HDL_TAP"TRUE";
"B \NAC \NWC"6;
"S \NAC"
BN"15"109;
%"TAP"
"1","(-5750,3125)","0","mstr_standard","I63";
;
CDS_LIB"mstr_standard"
BODY_TYPE"PLUMBING"
HDL_TAP"TRUE";
"B \NAC \NWC"6;
"S \NAC"
BN"17"107;
%"TAP"
"1","(-5750,3225)","0","mstr_standard","I64";
;
CDS_LIB"mstr_standard"
BODY_TYPE"PLUMBING"
HDL_TAP"TRUE";
"B \NAC \NWC"6;
"S \NAC"
BN"19"105;
%"TAP"
"1","(-5750,3175)","0","mstr_standard","I65";
;
CDS_LIB"mstr_standard"
BODY_TYPE"PLUMBING"
HDL_TAP"TRUE";
"B \NAC \NWC"6;
"S \NAC"
BN"18"106;
%"TAP"
"1","(-5750,3275)","0","mstr_standard","I66";
;
CDS_LIB"mstr_standard"
BODY_TYPE"PLUMBING"
HDL_TAP"TRUE";
"B \NAC \NWC"6;
"S \NAC"
BN"20"104;
%"TAP"
"1","(-5750,3325)","0","mstr_standard","I67";
;
CDS_LIB"mstr_standard"
BODY_TYPE"PLUMBING"
HDL_TAP"TRUE";
"B \NAC \NWC"6;
"S \NAC"
BN"21"176;
%"TAP"
"1","(-5750,3375)","0","mstr_standard","I68";
;
CDS_LIB"mstr_standard"
BODY_TYPE"PLUMBING"
HDL_TAP"TRUE";
"B \NAC \NWC"6;
"S \NAC"
BN"22"103;
%"TAP"
"1","(-5750,3475)","0","mstr_standard","I69";
;
CDS_LIB"mstr_standard"
BODY_TYPE"PLUMBING"
HDL_TAP"TRUE";
"B \NAC \NWC"6;
"S \NAC"
BN"24"101;
%"TAP"
"1","(-5750,3425)","0","mstr_standard","I70";
;
CDS_LIB"mstr_standard"
BODY_TYPE"PLUMBING"
HDL_TAP"TRUE";
"B \NAC \NWC"6;
"S \NAC"
BN"23"102;
%"TAP"
"1","(-5750,3525)","0","mstr_standard","I71";
;
CDS_LIB"mstr_standard"
BODY_TYPE"PLUMBING"
HDL_TAP"TRUE";
"B \NAC \NWC"6;
"S \NAC"
BN"25"100;
%"TAP"
"1","(-5750,3575)","0","mstr_standard","I72";
;
CDS_LIB"mstr_standard"
BODY_TYPE"PLUMBING"
HDL_TAP"TRUE";
"B \NAC \NWC"6;
"S \NAC"
BN"26"99;
%"TAP"
"1","(-5750,3625)","0","mstr_standard","I73";
;
CDS_LIB"mstr_standard"
BODY_TYPE"PLUMBING"
HDL_TAP"TRUE";
"B \NAC \NWC"6;
"S \NAC"
BN"27"98;
%"TAP"
"1","(-5750,3725)","0","mstr_standard","I74";
;
CDS_LIB"mstr_standard"
BODY_TYPE"PLUMBING"
HDL_TAP"TRUE";
"B \NAC \NWC"6;
"S \NAC"
BN"29"34;
%"TAP"
"1","(-5750,3675)","0","mstr_standard","I75";
;
CDS_LIB"mstr_standard"
BODY_TYPE"PLUMBING"
HDL_TAP"TRUE";
"B \NAC \NWC"6;
"S \NAC"
BN"28"97;
%"TAP"
"1","(-5750,3775)","0","mstr_standard","I76";
;
CDS_LIB"mstr_standard"
BODY_TYPE"PLUMBING"
HDL_TAP"TRUE";
"B \NAC \NWC"6;
"S \NAC"
BN"30"33;
%"TAP"
"1","(-5750,3825)","0","mstr_standard","I77";
;
CDS_LIB"mstr_standard"
BODY_TYPE"PLUMBING"
HDL_TAP"TRUE";
"B \NAC \NWC"6;
"S \NAC"
BN"31"96;
%"TAP"
"1","(-5750,3975)","0","mstr_standard","I78";
;
CDS_LIB"mstr_standard"
BODY_TYPE"PLUMBING"
HDL_TAP"TRUE";
"B \NAC \NWC"9;
"S \NAC"
BN"1"94;
%"TAP"
"1","(-5750,3925)","0","mstr_standard","I79";
;
CDS_LIB"mstr_standard"
BODY_TYPE"PLUMBING"
HDL_TAP"TRUE";
"B \NAC \NWC"9;
"S \NAC"
BN"0"95;
%"VCC_CORE"
"1","(-8500,3550)","0","mstr_symbols","I8";
;
HDL_POWER"P3V3_AUX"
CDS_LIB"mstr_symbols"
VOLTAGE"3.3"
ROOM"PVCCINFAON_CPU1_CTRL";
"A"22;
%"TAP"
"1","(-5750,4075)","0","mstr_standard","I80";
;
CDS_LIB"mstr_standard"
BODY_TYPE"PLUMBING"
HDL_TAP"TRUE";
"B \NAC \NWC"9;
"S \NAC"
BN"3"92;
%"TAP"
"1","(-5750,4125)","0","mstr_standard","I81";
;
CDS_LIB"mstr_standard"
BODY_TYPE"PLUMBING"
HDL_TAP"TRUE";
"B \NAC \NWC"9;
"S \NAC"
BN"4"91;
%"TAP"
"1","(-5750,4025)","0","mstr_standard","I82";
;
CDS_LIB"mstr_standard"
BODY_TYPE"PLUMBING"
HDL_TAP"TRUE";
"B \NAC \NWC"9;
"S \NAC"
BN"2"93;
%"TAP"
"1","(-7450,4775)","2","mstr_standard","I85";
;
CDS_LIB"mstr_standard"
BODY_TYPE"PLUMBING"
HDL_TAP"TRUE";
"B \NAC \NWC"15;
"S \NAC"
BN"0"50;
%"TAP"
"1","(-7450,4825)","2","mstr_standard","I86";
;
CDS_LIB"mstr_standard"
BODY_TYPE"PLUMBING"
HDL_TAP"TRUE";
"B \NAC \NWC"15;
"S \NAC"
BN"1"51;
%"TAP"
"1","(-7450,4875)","2","mstr_standard","I87";
;
CDS_LIB"mstr_standard"
BODY_TYPE"PLUMBING"
HDL_TAP"TRUE";
"B \NAC \NWC"15;
"S \NAC"
BN"2"53;
%"TAP"
"1","(-7450,4925)","2","mstr_standard","I88";
;
CDS_LIB"mstr_standard"
BODY_TYPE"PLUMBING"
HDL_TAP"TRUE";
"B \NAC \NWC"15;
"S \NAC"
BN"3"54;
%"TAP"
"1","(-7450,4975)","2","mstr_standard","I89";
;
CDS_LIB"mstr_standard"
BODY_TYPE"PLUMBING"
HDL_TAP"TRUE";
"B \NAC \NWC"15;
"S \NAC"
BN"4"56;
%"TAP"
"1","(-7450,5025)","2","mstr_standard","I90";
;
CDS_LIB"mstr_standard"
BODY_TYPE"PLUMBING"
HDL_TAP"TRUE";
"B \NAC \NWC"15;
"S \NAC"
BN"5"58;
%"TAP"
"1","(-7450,5075)","2","mstr_standard","I91";
;
CDS_LIB"mstr_standard"
BODY_TYPE"PLUMBING"
HDL_TAP"TRUE";
"B \NAC \NWC"15;
"S \NAC"
BN"6"59;
%"TAP"
"1","(-7450,5225)","2","mstr_standard","I92";
;
CDS_LIB"mstr_standard"
BODY_TYPE"PLUMBING"
HDL_TAP"TRUE";
"B \NAC \NWC"7;
"S \NAC"
BN"1"173;
%"TAP"
"1","(-7450,5175)","2","mstr_standard","I93";
;
CDS_LIB"mstr_standard"
BODY_TYPE"PLUMBING"
HDL_TAP"TRUE";
"B \NAC \NWC"7;
"S \NAC"
BN"0"127;
%"TAP"
"1","(-7450,5275)","2","mstr_standard","I94";
;
CDS_LIB"mstr_standard"
BODY_TYPE"PLUMBING"
HDL_TAP"TRUE";
"B \NAC \NWC"7;
"S \NAC"
BN"2"52;
%"TAP"
"1","(-7450,5325)","2","mstr_standard","I95";
;
CDS_LIB"mstr_standard"
BODY_TYPE"PLUMBING"
HDL_TAP"TRUE";
"B \NAC \NWC"7;
"S \NAC"
BN"3"174;
%"TAP"
"1","(-7450,5375)","2","mstr_standard","I96";
;
CDS_LIB"mstr_standard"
BODY_TYPE"PLUMBING"
HDL_TAP"TRUE";
"B \NAC \NWC"7;
"S \NAC"
BN"4"55;
%"TAP"
"1","(-7450,5425)","2","mstr_standard","I97";
;
CDS_LIB"mstr_standard"
BODY_TYPE"PLUMBING"
HDL_TAP"TRUE";
"B \NAC \NWC"7;
"S \NAC"
BN"5"57;
%"TAP"
"1","(-7450,5475)","2","mstr_standard","I98";
;
CDS_LIB"mstr_standard"
BODY_TYPE"PLUMBING"
HDL_TAP"TRUE";
"B \NAC \NWC"7;
"S \NAC"
BN"6"175;
%"TAP"
"1","(-5750,4225)","0","mstr_standard","I99";
;
CDS_LIB"mstr_standard"
BODY_TYPE"PLUMBING"
HDL_TAP"TRUE";
"B \NAC \NWC"9;
"S \NAC"
BN"6"89;
END.
